(kicad_pcb
	(version 20260206)
	(generator "pcbnew")
	(generator_version "10.0")
	(general
		(thickness 1.6)
		(legacy_teardrops no)
	)
	(paper "A4")
	(title_block
		(title "01162023_DA0F0TEBIF0_F0T_Expander_BD_F_brd_V02_OCP.brd")
		(comment 1 "Grand Teton / footprints 7784-7795 of 9728")
	)
	(layers
		(0 "F.Cu" signal "TOP")
		(4 "In1.Cu" signal "GND")
		(6 "In2.Cu" signal "VCC")
		(8 "In3.Cu" signal "VCC1")
		(10 "In4.Cu" signal "GND1")
		(12 "In5.Cu" signal "IN1")
		(14 "In6.Cu" signal "GND2")
		(16 "In7.Cu" signal "IN2")
		(18 "In8.Cu" signal "GND3")
		(20 "In9.Cu" signal "IN3")
		(22 "In10.Cu" signal "GND4")
		(24 "In11.Cu" signal "IN4")
		(26 "In12.Cu" signal "GND5")
		(28 "In13.Cu" signal "IN5")
		(30 "In14.Cu" signal "GND6")
		(32 "In15.Cu" signal "IN6")
		(34 "In16.Cu" signal "GND7")
		(2 "B.Cu" signal "BOTTOM")
		(9 "F.Adhes" user "F.Adhesive")
		(11 "B.Adhes" user "B.Adhesive")
		(13 "F.Paste" user "Package Geometry/Pastemask Top")
		(15 "B.Paste" user "Package Geometry/Pastemask Bottom")
		(5 "F.SilkS" user "Ref Des/Silkscreen Top")
		(7 "B.SilkS" user "Ref Des/Silkscreen Bottom")
		(1 "F.Mask" user "Board Geometry/Soldermask Top")
		(3 "B.Mask" user "Board Geometry/Soldermask Bottom")
		(17 "Dwgs.User" user "User.Drawings")
		(19 "Cmts.User" user "User.Comments")
		(21 "Eco1.User" user "User.Eco1")
		(23 "Eco2.User" user "User.Eco2")
		(25 "Edge.Cuts" user "Board Geometry/Outline")
		(27 "Margin" user)
		(31 "F.CrtYd" user "Package Geometry/Place Bound Top")
		(29 "B.CrtYd" user "Package Geometry/Place Bound Bottom")
		(35 "F.Fab" user "Ref Des/Assembly Top")
		(33 "B.Fab" user "Ref Des/Assembly Bottom")
	)
	(footprint ""
		(layer "B.Cu")
		(at 219.939362 -288.197544)
		(property "Reference" "PC233"
			(at 0 0 0)
			(layer "B.SilkS")
			(hide yes)
			(effects
				(font
					(size 1.27 1.27)
				)
				(justify mirror)
			)
		)
		(property "Value" ""
			(at 0 0 0)
			(layer "B.Fab")
			(effects
				(font
					(size 1.27 1.27)
				)
				(justify mirror)
			)
		)
		(duplicate_pad_numbers_are_jumpers no)
		(fp_line
			(start -1.524 -0.762)
			(end -1.524 0.762)
			(stroke
				(width 0.1524)
				(type default)
			)
			(layer "B.SilkS")
		)
		(fp_line
			(start -1.524 0.762)
			(end 1.524 0.762)
			(stroke
				(width 0.1524)
				(type default)
			)
			(layer "B.SilkS")
		)
		(fp_line
			(start 1.524 -0.762)
			(end -1.524 -0.762)
			(stroke
				(width 0.1524)
				(type default)
			)
			(layer "B.SilkS")
		)
		(fp_line
			(start 1.524 0.762)
			(end 1.524 -0.762)
			(stroke
				(width 0.1524)
				(type default)
			)
			(layer "B.SilkS")
		)
		(fp_line
			(start -1.1049 -0.724916)
			(end 1.1049 -0.724916)
			(stroke
				(width 0.1)
				(type default)
			)
			(layer "B.Fab")
		)
		(fp_line
			(start -1.1049 0.724916)
			(end -1.1049 -0.724916)
			(stroke
				(width 0.1)
				(type default)
			)
			(layer "B.Fab")
		)
		(fp_line
			(start 1.1049 -0.724916)
			(end 1.1049 0.724916)
			(stroke
				(width 0.1)
				(type default)
			)
			(layer "B.Fab")
		)
		(fp_line
			(start 1.1049 0.724916)
			(end -1.1049 0.724916)
			(stroke
				(width 0.1)
				(type default)
			)
			(layer "B.Fab")
		)
		(pad "1" smd rect
			(at 0.889 0)
			(size 1.016 1.27)
			(layers "B.Cu" "B.Mask" "B.Paste")
			(net "P1V25_PEX1_R")
		)
		(pad "2" smd rect
			(at -0.889 0)
			(size 1.016 1.27)
			(layers "B.Cu" "B.Mask" "B.Paste")
			(net "GND")
		)
	)
	(footprint ""
		(layer "B.Cu")
		(at 178.599846 -290.199826 90)
		(property "Reference" "C1491"
			(at 0 0 90)
			(layer "B.SilkS")
			(hide yes)
			(effects
				(font
					(size 1.27 1.27)
				)
				(justify mirror)
			)
		)
		(property "Value" ""
			(at 0 0 90)
			(layer "B.Fab")
			(effects
				(font
					(size 1.27 1.27)
				)
				(justify mirror)
			)
		)
		(duplicate_pad_numbers_are_jumpers no)
		(fp_line
			(start 0.299974 -0.150114)
			(end -0.299974 -0.150114)
			(stroke
				(width 0.1)
				(type default)
			)
			(layer "B.Fab")
		)
		(fp_line
			(start -0.299974 -0.150114)
			(end -0.299974 0.150114)
			(stroke
				(width 0.1)
				(type default)
			)
			(layer "B.Fab")
		)
		(fp_line
			(start 0.299974 0.150114)
			(end 0.299974 -0.150114)
			(stroke
				(width 0.1)
				(type default)
			)
			(layer "B.Fab")
		)
		(fp_line
			(start -0.299974 0.150114)
			(end 0.299974 0.150114)
			(stroke
				(width 0.1)
				(type default)
			)
			(layer "B.Fab")
		)
		(pad "1" smd rect
			(at 0.2667 0 270)
			(size 0.3048 0.381)
			(layers "B.Cu" "B.Mask" "B.Paste")
			(net "P0V8_SERDES_VDDA_PEX1")
		)
		(pad "2" smd rect
			(at -0.2667 0 270)
			(size 0.3048 0.381)
			(layers "B.Cu" "B.Mask" "B.Paste")
			(net "GND")
		)
	)
	(footprint ""
		(layer "B.Cu")
		(at 331.408532 -212.34019)
		(property "Reference" "C2053"
			(at 0 0 0)
			(layer "B.SilkS")
			(hide yes)
			(effects
				(font
					(size 1.27 1.27)
				)
				(justify mirror)
			)
		)
		(property "Value" ""
			(at 0 0 0)
			(layer "B.Fab")
			(effects
				(font
					(size 1.27 1.27)
				)
				(justify mirror)
			)
		)
		(duplicate_pad_numbers_are_jumpers no)
		(fp_line
			(start -0.69215 -0.2921)
			(end -0.69215 0.2921)
			(stroke
				(width 0.1524)
				(type default)
			)
			(layer "B.SilkS")
		)
		(fp_line
			(start -0.69215 0.2921)
			(end 0.69215 0.2921)
			(stroke
				(width 0.1524)
				(type default)
			)
			(layer "B.SilkS")
		)
		(fp_line
			(start 0.69215 -0.2921)
			(end -0.69215 -0.2921)
			(stroke
				(width 0.1524)
				(type default)
			)
			(layer "B.SilkS")
		)
		(fp_line
			(start 0.69215 0.2921)
			(end 0.69215 -0.2921)
			(stroke
				(width 0.1524)
				(type default)
			)
			(layer "B.SilkS")
		)
		(fp_line
			(start -0.51435 -0.2794)
			(end -0.51435 0.2794)
			(stroke
				(width 0.1)
				(type default)
			)
			(layer "B.Fab")
		)
		(fp_line
			(start -0.51435 0.2794)
			(end 0.51435 0.2794)
			(stroke
				(width 0.1)
				(type default)
			)
			(layer "B.Fab")
		)
		(fp_line
			(start 0.51435 -0.2794)
			(end -0.51435 -0.2794)
			(stroke
				(width 0.1)
				(type default)
			)
			(layer "B.Fab")
		)
		(fp_line
			(start 0.51435 0.2794)
			(end 0.51435 -0.2794)
			(stroke
				(width 0.1)
				(type default)
			)
			(layer "B.Fab")
		)
		(pad "1" smd circle
			(at 0.40005 0 180)
			(size 0 0)
			(layers "B.Cu" "B.Mask" "B.Paste")
			(net "P3V3_FPGA_VCCIO2")
		)
		(pad "2" smd circle
			(at -0.40005 0 180)
			(size 0 0)
			(layers "B.Cu" "B.Mask" "B.Paste")
			(net "GND")
		)
		(zone
			(layer "B.Cu")
			(hatch none 0.5)
			(connect_pads
				(clearance 0)
			)
			(min_thickness 0.25)
			(keepout
				(tracks not_allowed)
				(vias allowed)
				(pads allowed)
				(copperpour not_allowed)
				(footprints allowed)
			)
			(placement
				(enabled no)
				(sheetname "")
			)
			(fill
				(thermal_gap 0.5)
				(thermal_bridge_width 0.5)
				(island_removal_mode 0)
			)
			(polygon
				(pts
					(xy 331.599032 -212.25256) (xy 331.507592 -212.194394) (xy 331.308202 -212.194394) (xy 331.218032 -212.25256)
					(xy 331.218032 -212.42782) (xy 331.308202 -212.48624) (xy 331.507592 -212.48624) (xy 331.599032 -212.428074)
				)
			)
		)
	)
	(footprint ""
		(layer "B.Cu")
		(at 56.799988 -299.699934 -90)
		(property "Reference" "C1205"
			(at 0 0 90)
			(layer "B.SilkS")
			(hide yes)
			(effects
				(font
					(size 1.27 1.27)
				)
				(justify mirror)
			)
		)
		(property "Value" ""
			(at 0 0 90)
			(layer "B.Fab")
			(effects
				(font
					(size 1.27 1.27)
				)
				(justify mirror)
			)
		)
		(duplicate_pad_numbers_are_jumpers no)
		(fp_line
			(start -0.299974 0.150114)
			(end 0.299974 0.150114)
			(stroke
				(width 0.1)
				(type default)
			)
			(layer "B.Fab")
		)
		(fp_line
			(start 0.299974 0.150114)
			(end 0.299974 -0.150114)
			(stroke
				(width 0.1)
				(type default)
			)
			(layer "B.Fab")
		)
		(fp_line
			(start -0.299974 -0.150114)
			(end -0.299974 0.150114)
			(stroke
				(width 0.1)
				(type default)
			)
			(layer "B.Fab")
		)
		(fp_line
			(start 0.299974 -0.150114)
			(end -0.299974 -0.150114)
			(stroke
				(width 0.1)
				(type default)
			)
			(layer "B.Fab")
		)
		(pad "1" smd rect
			(at 0.2667 0 90)
			(size 0.3048 0.381)
			(layers "B.Cu" "B.Mask" "B.Paste")
			(net "P0V8_SERDES_VDDA_PEX0")
		)
		(pad "2" smd rect
			(at -0.2667 0 90)
			(size 0.3048 0.381)
			(layers "B.Cu" "B.Mask" "B.Paste")
			(net "GND")
		)
	)
	(footprint ""
		(layer "B.Cu")
		(at 410.799788 -288.299906 90)
		(property "Reference" "C3446"
			(at 0 0 90)
			(layer "B.SilkS")
			(hide yes)
			(effects
				(font
					(size 1.27 1.27)
				)
				(justify mirror)
			)
		)
		(property "Value" ""
			(at 0 0 90)
			(layer "B.Fab")
			(effects
				(font
					(size 1.27 1.27)
				)
				(justify mirror)
			)
		)
		(duplicate_pad_numbers_are_jumpers no)
		(fp_line
			(start 0.299974 -0.150114)
			(end -0.299974 -0.150114)
			(stroke
				(width 0.1)
				(type default)
			)
			(layer "B.Fab")
		)
		(fp_line
			(start -0.299974 -0.150114)
			(end -0.299974 0.150114)
			(stroke
				(width 0.1)
				(type default)
			)
			(layer "B.Fab")
		)
		(fp_line
			(start 0.299974 0.150114)
			(end 0.299974 -0.150114)
			(stroke
				(width 0.1)
				(type default)
			)
			(layer "B.Fab")
		)
		(fp_line
			(start -0.299974 0.150114)
			(end 0.299974 0.150114)
			(stroke
				(width 0.1)
				(type default)
			)
			(layer "B.Fab")
		)
		(pad "1" smd rect
			(at 0.2667 0 270)
			(size 0.3048 0.381)
			(layers "B.Cu" "B.Mask" "B.Paste")
			(net "P1V25_PEX3")
		)
		(pad "2" smd rect
			(at -0.2667 0 270)
			(size 0.3048 0.381)
			(layers "B.Cu" "B.Mask" "B.Paste")
			(net "GND")
		)
	)
	(footprint ""
		(layer "B.Cu")
		(at 412.699962 -288.299906 90)
		(property "Reference" "C3443"
			(at 0 0 90)
			(layer "B.SilkS")
			(hide yes)
			(effects
				(font
					(size 1.27 1.27)
				)
				(justify mirror)
			)
		)
		(property "Value" ""
			(at 0 0 90)
			(layer "B.Fab")
			(effects
				(font
					(size 1.27 1.27)
				)
				(justify mirror)
			)
		)
		(duplicate_pad_numbers_are_jumpers no)
		(fp_line
			(start 0.299974 -0.150114)
			(end -0.299974 -0.150114)
			(stroke
				(width 0.1)
				(type default)
			)
			(layer "B.Fab")
		)
		(fp_line
			(start -0.299974 -0.150114)
			(end -0.299974 0.150114)
			(stroke
				(width 0.1)
				(type default)
			)
			(layer "B.Fab")
		)
		(fp_line
			(start 0.299974 0.150114)
			(end 0.299974 -0.150114)
			(stroke
				(width 0.1)
				(type default)
			)
			(layer "B.Fab")
		)
		(fp_line
			(start -0.299974 0.150114)
			(end 0.299974 0.150114)
			(stroke
				(width 0.1)
				(type default)
			)
			(layer "B.Fab")
		)
		(pad "1" smd rect
			(at 0.2667 0 270)
			(size 0.3048 0.381)
			(layers "B.Cu" "B.Mask" "B.Paste")
			(net "P1V25_PEX3")
		)
		(pad "2" smd rect
			(at -0.2667 0 270)
			(size 0.3048 0.381)
			(layers "B.Cu" "B.Mask" "B.Paste")
			(net "GND")
		)
	)
	(footprint ""
		(layer "B.Cu")
		(at 102.853236 -81.655666 -90)
		(property "Reference" "L13"
			(at 0 0 90)
			(layer "B.SilkS")
			(hide yes)
			(effects
				(font
					(size 1.27 1.27)
				)
				(justify mirror)
			)
		)
		(property "Value" ""
			(at 0 0 90)
			(layer "B.Fab")
			(effects
				(font
					(size 1.27 1.27)
				)
				(justify mirror)
			)
		)
		(duplicate_pad_numbers_are_jumpers no)
		(fp_line
			(start -1.27 0.5842)
			(end 1.27 0.5842)
			(stroke
				(width 0.1524)
				(type default)
			)
			(layer "B.SilkS")
		)
		(fp_line
			(start -1.27 0.5842)
			(end -1.27 -0.5842)
			(stroke
				(width 0.1524)
				(type default)
			)
			(layer "B.SilkS")
		)
		(fp_line
			(start 1.27 0.5842)
			(end 1.27 -0.5842)
			(stroke
				(width 0.1524)
				(type default)
			)
			(layer "B.SilkS")
		)
		(fp_line
			(start 1.27 -0.5588)
			(end 1.27 -0.5842)
			(stroke
				(width 0.1524)
				(type default)
			)
			(layer "B.SilkS")
		)
		(fp_line
			(start 1.27 -0.5842)
			(end -1.27 -0.5842)
			(stroke
				(width 0.1524)
				(type default)
			)
			(layer "B.SilkS")
		)
		(fp_line
			(start -0.9144 0.508)
			(end 0.9144 0.508)
			(stroke
				(width 0.1)
				(type default)
			)
			(layer "B.Fab")
		)
		(fp_line
			(start 0.9144 0.508)
			(end 0.9144 0.406654)
			(stroke
				(width 0.1)
				(type default)
			)
			(layer "B.Fab")
		)
		(fp_line
			(start 0.9144 0.406654)
			(end 1.194308 0.406654)
			(stroke
				(width 0.1)
				(type default)
			)
			(layer "B.Fab")
		)
		(fp_line
			(start 1.194308 0.406654)
			(end 1.194308 -0.406654)
			(stroke
				(width 0.1)
				(type default)
			)
			(layer "B.Fab")
		)
		(fp_line
			(start -1.1938 0.4064)
			(end -0.9144 0.4064)
			(stroke
				(width 0.1)
				(type default)
			)
			(layer "B.Fab")
		)
		(fp_line
			(start -0.9144 0.4064)
			(end -0.9144 0.508)
			(stroke
				(width 0.1)
				(type default)
			)
			(layer "B.Fab")
		)
		(fp_line
			(start -1.1938 -0.406654)
			(end -1.1938 0.4064)
			(stroke
				(width 0.1)
				(type default)
			)
			(layer "B.Fab")
		)
		(fp_line
			(start -0.9144 -0.406654)
			(end -1.1938 -0.406654)
			(stroke
				(width 0.1)
				(type default)
			)
			(layer "B.Fab")
		)
		(fp_line
			(start 0.9144 -0.406654)
			(end 0.9144 -0.508)
			(stroke
				(width 0.1)
				(type default)
			)
			(layer "B.Fab")
		)
		(fp_line
			(start 1.194308 -0.406654)
			(end 0.9144 -0.406654)
			(stroke
				(width 0.1)
				(type default)
			)
			(layer "B.Fab")
		)
		(fp_line
			(start -0.9144 -0.508)
			(end -0.9144 -0.406654)
			(stroke
				(width 0.1)
				(type default)
			)
			(layer "B.Fab")
		)
		(fp_line
			(start 0.9144 -0.508)
			(end -0.9144 -0.508)
			(stroke
				(width 0.1)
				(type default)
			)
			(layer "B.Fab")
		)
		(pad "1" smd rect
			(at 0.7366 0 180)
			(size 0.7112 0.8128)
			(layers "B.Cu" "B.Mask" "B.Paste")
			(net "P3V3")
		)
		(pad "2" smd rect
			(at -0.7366 0 180)
			(size 0.7112 0.8128)
			(layers "B.Cu" "B.Mask" "B.Paste")
			(net "P3V3_VDD_9ZXL0851_0_7")
		)
	)
	(footprint ""
		(layer "B.Cu")
		(at 298.024804 -286.399732 90)
		(property "Reference" "C3324"
			(at 0 0 90)
			(layer "B.SilkS")
			(hide yes)
			(effects
				(font
					(size 1.27 1.27)
				)
				(justify mirror)
			)
		)
		(property "Value" ""
			(at 0 0 90)
			(layer "B.Fab")
			(effects
				(font
					(size 1.27 1.27)
				)
				(justify mirror)
			)
		)
		(duplicate_pad_numbers_are_jumpers no)
		(fp_line
			(start 0.299974 -0.150114)
			(end -0.299974 -0.150114)
			(stroke
				(width 0.1)
				(type default)
			)
			(layer "B.Fab")
		)
		(fp_line
			(start -0.299974 -0.150114)
			(end -0.299974 0.150114)
			(stroke
				(width 0.1)
				(type default)
			)
			(layer "B.Fab")
		)
		(fp_line
			(start 0.299974 0.150114)
			(end 0.299974 -0.150114)
			(stroke
				(width 0.1)
				(type default)
			)
			(layer "B.Fab")
		)
		(fp_line
			(start -0.299974 0.150114)
			(end 0.299974 0.150114)
			(stroke
				(width 0.1)
				(type default)
			)
			(layer "B.Fab")
		)
		(pad "1" smd rect
			(at 0.2667 0 270)
			(size 0.3048 0.381)
			(layers "B.Cu" "B.Mask" "B.Paste")
			(net "P1V25_SERDES_VDDPLL_PEX2")
		)
		(pad "2" smd rect
			(at -0.2667 0 270)
			(size 0.3048 0.381)
			(layers "B.Cu" "B.Mask" "B.Paste")
			(net "GND")
		)
	)
	(footprint ""
		(layer "B.Cu")
		(at 449.830698 -272.697194)
		(property "Reference" "C4391"
			(at 0 0 0)
			(layer "B.SilkS")
			(hide yes)
			(effects
				(font
					(size 1.27 1.27)
				)
				(justify mirror)
			)
		)
		(property "Value" ""
			(at 0 0 0)
			(layer "B.Fab")
			(effects
				(font
					(size 1.27 1.27)
				)
				(justify mirror)
			)
		)
		(duplicate_pad_numbers_are_jumpers no)
		(fp_line
			(start -0.299974 -0.150114)
			(end -0.299974 0.150114)
			(stroke
				(width 0.1)
				(type default)
			)
			(layer "B.Fab")
		)
		(fp_line
			(start -0.299974 0.150114)
			(end 0.299974 0.150114)
			(stroke
				(width 0.1)
				(type default)
			)
			(layer "B.Fab")
		)
		(fp_line
			(start 0.299974 -0.150114)
			(end -0.299974 -0.150114)
			(stroke
				(width 0.1)
				(type default)
			)
			(layer "B.Fab")
		)
		(fp_line
			(start 0.299974 0.150114)
			(end 0.299974 -0.150114)
			(stroke
				(width 0.1)
				(type default)
			)
			(layer "B.Fab")
		)
		(pad "1" smd rect
			(at 0.2667 0 180)
			(size 0.3048 0.381)
			(layers "B.Cu" "B.Mask" "B.Paste")
			(net "P1V25_PEX3")
		)
		(pad "2" smd rect
			(at -0.2667 0 180)
			(size 0.3048 0.381)
			(layers "B.Cu" "B.Mask" "B.Paste")
			(net "GND")
		)
	)
	(footprint ""
		(layer "B.Cu")
		(at 293.74973 -299.699934 -90)
		(property "Reference" "C1745"
			(at 0 0 90)
			(layer "B.SilkS")
			(hide yes)
			(effects
				(font
					(size 1.27 1.27)
				)
				(justify mirror)
			)
		)
		(property "Value" ""
			(at 0 0 90)
			(layer "B.Fab")
			(effects
				(font
					(size 1.27 1.27)
				)
				(justify mirror)
			)
		)
		(duplicate_pad_numbers_are_jumpers no)
		(fp_line
			(start -0.299974 0.150114)
			(end 0.299974 0.150114)
			(stroke
				(width 0.1)
				(type default)
			)
			(layer "B.Fab")
		)
		(fp_line
			(start 0.299974 0.150114)
			(end 0.299974 -0.150114)
			(stroke
				(width 0.1)
				(type default)
			)
			(layer "B.Fab")
		)
		(fp_line
			(start -0.299974 -0.150114)
			(end -0.299974 0.150114)
			(stroke
				(width 0.1)
				(type default)
			)
			(layer "B.Fab")
		)
		(fp_line
			(start 0.299974 -0.150114)
			(end -0.299974 -0.150114)
			(stroke
				(width 0.1)
				(type default)
			)
			(layer "B.Fab")
		)
		(pad "1" smd rect
			(at 0.2667 0 90)
			(size 0.3048 0.381)
			(layers "B.Cu" "B.Mask" "B.Paste")
			(net "P0V8_SERDES_VDDA_PEX2")
		)
		(pad "2" smd rect
			(at -0.2667 0 90)
			(size 0.3048 0.381)
			(layers "B.Cu" "B.Mask" "B.Paste")
			(net "GND")
		)
	)
	(footprint ""
		(layer "B.Cu")
		(at 301.349918 -300.174914 180)
		(property "Reference" "C3362"
			(at 0 0 0)
			(layer "B.SilkS")
			(hide yes)
			(effects
				(font
					(size 1.27 1.27)
				)
				(justify mirror)
			)
		)
		(property "Value" ""
			(at 0 0 0)
			(layer "B.Fab")
			(effects
				(font
					(size 1.27 1.27)
				)
				(justify mirror)
			)
		)
		(duplicate_pad_numbers_are_jumpers no)
		(fp_line
			(start 0.299974 0.150114)
			(end 0.299974 -0.150114)
			(stroke
				(width 0.1)
				(type default)
			)
			(layer "B.Fab")
		)
		(fp_line
			(start 0.299974 -0.150114)
			(end -0.299974 -0.150114)
			(stroke
				(width 0.1)
				(type default)
			)
			(layer "B.Fab")
		)
		(fp_line
			(start -0.299974 0.150114)
			(end 0.299974 0.150114)
			(stroke
				(width 0.1)
				(type default)
			)
			(layer "B.Fab")
		)
		(fp_line
			(start -0.299974 -0.150114)
			(end -0.299974 0.150114)
			(stroke
				(width 0.1)
				(type default)
			)
			(layer "B.Fab")
		)
		(pad "1" smd rect
			(at 0.2667 0)
			(size 0.3048 0.381)
			(layers "B.Cu" "B.Mask" "B.Paste")
			(net "P1V8_VDDA_PEX2")
		)
		(pad "2" smd rect
			(at -0.2667 0)
			(size 0.3048 0.381)
			(layers "B.Cu" "B.Mask" "B.Paste")
			(net "GND")
		)
	)
	(footprint ""
		(layer "B.Cu")
		(at 167.675052 -305.399948 -90)
		(property "Reference" "C3157"
			(at 0 0 90)
			(layer "B.SilkS")
			(hide yes)
			(effects
				(font
					(size 1.27 1.27)
				)
				(justify mirror)
			)
		)
		(property "Value" ""
			(at 0 0 90)
			(layer "B.Fab")
			(effects
				(font
					(size 1.27 1.27)
				)
				(justify mirror)
			)
		)
		(duplicate_pad_numbers_are_jumpers no)
		(fp_line
			(start -0.299974 0.150114)
			(end 0.299974 0.150114)
			(stroke
				(width 0.1)
				(type default)
			)
			(layer "B.Fab")
		)
		(fp_line
			(start 0.299974 0.150114)
			(end 0.299974 -0.150114)
			(stroke
				(width 0.1)
				(type default)
			)
			(layer "B.Fab")
		)
		(fp_line
			(start -0.299974 -0.150114)
			(end -0.299974 0.150114)
			(stroke
				(width 0.1)
				(type default)
			)
			(layer "B.Fab")
		)
		(fp_line
			(start 0.299974 -0.150114)
			(end -0.299974 -0.150114)
			(stroke
				(width 0.1)
				(type default)
			)
			(layer "B.Fab")
		)
		(pad "1" smd rect
			(at 0.2667 0 90)
			(size 0.3048 0.381)
			(layers "B.Cu" "B.Mask" "B.Paste")
			(net "P1V25_SERDES_VDDPLL_PEX1")
		)
		(pad "2" smd rect
			(at -0.2667 0 90)
			(size 0.3048 0.381)
			(layers "B.Cu" "B.Mask" "B.Paste")
			(net "GND")
		)
	)
)
